(kicad_pcb
	(version 20241229)
	(generator "pcbnew")
	(generator_version "9.0")
	(general
		(thickness 1.6)
		(legacy_teardrops no)
	)
	(paper "A4")
	(title_block
		(title "GMSL Deserializer")
		(date "2025-10-09")
		(rev "1.0.4")
		(company "Antmicro Ltd")
		(comment 1 "www.antmicro.com")
		(comment 9 "footprints 222-227 of 235")
	)
	(layers
		(0 "F.Cu" signal)
		(4 "In1.Cu" power)
		(6 "In2.Cu" power)
		(2 "B.Cu" signal)
		(9 "F.Adhes" user "F.Adhesive")
		(11 "B.Adhes" user "B.Adhesive")
		(13 "F.Paste" user)
		(15 "B.Paste" user)
		(5 "F.SilkS" user "F.Silkscreen")
		(7 "B.SilkS" user "B.Silkscreen")
		(1 "F.Mask" user)
		(3 "B.Mask" user)
		(17 "Dwgs.User" user "User.Drawings")
		(19 "Cmts.User" user "User.Comments")
		(21 "Eco1.User" user "User.Eco1")
		(23 "Eco2.User" user "User.Eco2")
		(25 "Edge.Cuts" user)
		(27 "Margin" user)
		(31 "F.CrtYd" user "F.Courtyard")
		(29 "B.CrtYd" user "B.Courtyard")
		(35 "F.Fab" user)
		(33 "B.Fab" user)
	)
	(footprint "antmicro-footprints:C_0402_1005Metric"
		(layer "B.Cu")
		(at 143.51 76.454 -45)
		(descr "Capacitor SMD 0402")
		(tags "capacitor SMD 0402")
		(property "Reference" "C36"
			(at -1.52271 0.22729 315)
			(unlocked yes)
			(layer "B.SilkS")
			(effects
				(font
					(size 0.7 0.7)
					(thickness 0.15)
				)
				(justify left bottom mirror)
			)
		)
		(property "Value" "C_10u_0402"
			(at -1.022927 -2.155213 135)
			(layer "B.Fab")
			(effects
				(font
					(size 0.7 0.7)
					(thickness 0.15)
				)
				(justify left bottom mirror)
			)
		)
		(property "Datasheet" "https://www.yageo.com/en/Chart/Download/pdf/CC0402MRX5R5BB106"
			(at 0 0 315)
			(layer "F.Fab")
			(hide yes)
			(effects
				(font
					(size 1.27 1.27)
					(thickness 0.15)
				)
			)
		)
		(property "Description" "SMD Multilayer Ceramic Capacitor, 10 µF, 6.3 V, 0402 [1005 Metric], ± 20%, X5R, CC Series"
			(at 0 0 315)
			(layer "F.Fab")
			(hide yes)
			(effects
				(font
					(size 1.27 1.27)
					(thickness 0.15)
				)
			)
		)
		(property "Author" "Antmicro"
			(at -12.028036 123.869753 0)
			(layer "B.Fab")
			(hide yes)
			(effects
				(font
					(size 1 1)
					(thickness 0.15)
				)
				(justify mirror)
			)
		)
		(property "Dielectric" ""
			(at -12.028036 123.869753 0)
			(layer "B.Fab")
			(hide yes)
			(effects
				(font
					(size 1 1)
					(thickness 0.15)
				)
				(justify mirror)
			)
		)
		(property "License" "Apache-2.0"
			(at -12.028036 123.869753 0)
			(layer "B.Fab")
			(hide yes)
			(effects
				(font
					(size 1 1)
					(thickness 0.15)
				)
				(justify mirror)
			)
		)
		(property "MPN" "CC0402MRX5R5BB106"
			(at -12.028036 123.869753 0)
			(layer "B.Fab")
			(hide yes)
			(effects
				(font
					(size 1 1)
					(thickness 0.15)
				)
				(justify mirror)
			)
		)
		(property "Manufacturer" "YAGEO"
			(at -12.028036 123.869753 0)
			(layer "B.Fab")
			(hide yes)
			(effects
				(font
					(size 1 1)
					(thickness 0.15)
				)
				(justify mirror)
			)
		)
		(property "Val" "10u"
			(at -12.028036 123.869753 0)
			(layer "B.Fab")
			(hide yes)
			(effects
				(font
					(size 1 1)
					(thickness 0.15)
				)
				(justify mirror)
			)
		)
		(property "Voltage" ""
			(at -12.028036 123.869753 0)
			(layer "B.Fab")
			(hide yes)
			(effects
				(font
					(size 1 1)
					(thickness 0.15)
				)
				(justify mirror)
			)
		)
		(sheetname "/Deserializer/")
		(sheetfile "deserializer.kicad_sch")
		(attr smd)
		(fp_poly
			(pts
				(xy -0.925 0.47) (xy 0.925 0.47) (xy 0.925 -0.47) (xy -0.925 -0.47)
			)
			(stroke
				(width 0.05)
				(type default)
			)
			(fill no)
			(layer "B.CrtYd")
		)
		(fp_line
			(start -0.494 0.25)
			(end -0.494 -0.248)
			(stroke
				(width 0.15)
				(type solid)
			)
			(layer "B.Fab")
		)
		(fp_line
			(start -0.494 -0.248)
			(end 0.504 -0.248)
			(stroke
				(width 0.15)
				(type solid)
			)
			(layer "B.Fab")
		)
		(fp_line
			(start 0.504 0.25)
			(end -0.494 0.25)
			(stroke
				(width 0.15)
				(type solid)
			)
			(layer "B.Fab")
		)
		(fp_line
			(start 0.504 -0.248)
			(end 0.504 0.25)
			(stroke
				(width 0.15)
				(type solid)
			)
			(layer "B.Fab")
		)
		(pad "1" smd roundrect
			(at -0.48 0 315)
			(size 0.59 0.64)
			(layers "B.Cu" "B.Mask" "B.Paste")
			(roundrect_rratio 0.25)
			(net 1 "GND")
			(pintype "passive")
		)
		(pad "2" smd roundrect
			(at 0.48 0 315)
			(size 0.59 0.64)
			(layers "B.Cu" "B.Mask" "B.Paste")
			(roundrect_rratio 0.25)
			(net 26 "/Deserializer/VDD_1.8V")
			(pintype "passive")
		)
	)
	(footprint "antmicro-footprints:R_0402_1005Metric"
		(layer "B.Cu")
		(at 149.33434 96.355897 90)
		(descr "Resistor SMD 0402")
		(tags "resistor SMD 0402")
		(property "Reference" "R75"
			(at 5.726288 0.424322 90)
			(layer "B.SilkS")
			(effects
				(font
					(size 0.7 0.7)
					(thickness 0.15)
				)
				(justify right bottom mirror)
			)
		)
		(property "Value" "R_1k65_0402"
			(at -1.011843 -1.772046 90)
			(layer "B.Fab")
			(effects
				(font
					(size 0.7 0.7)
					(thickness 0.15)
				)
				(justify right bottom mirror)
			)
		)
		(property "Datasheet" "https://www.farnell.com/datasheets/3795017.pdf"
			(at 0 0 90)
			(layer "F.Fab")
			(hide yes)
			(effects
				(font
					(size 1.27 1.27)
					(thickness 0.15)
				)
			)
		)
		(property "Description" "SMD Chip Resistor, 1.65 kohm, ± 1%, 63 mW, 0402 [1005 Metric], Thick Film, General Purpose"
			(at 0 0 90)
			(layer "F.Fab")
			(hide yes)
			(effects
				(font
					(size 1.27 1.27)
					(thickness 0.15)
				)
			)
		)
		(property "Author" "Antmicro"
			(at 323.23721 57.589586 135)
			(layer "B.Fab")
			(hide yes)
			(effects
				(font
					(size 1 1)
					(thickness 0.15)
				)
				(justify mirror)
			)
		)
		(property "License" "Apache-2.0"
			(at 323.23721 57.589586 135)
			(layer "B.Fab")
			(hide yes)
			(effects
				(font
					(size 1 1)
					(thickness 0.15)
				)
				(justify mirror)
			)
		)
		(property "MPN" "RC0402FR-071K65L"
			(at 323.23721 57.589586 135)
			(layer "B.Fab")
			(hide yes)
			(effects
				(font
					(size 1 1)
					(thickness 0.15)
				)
				(justify mirror)
			)
		)
		(property "Manufacturer" "YAGEO"
			(at 323.23721 57.589586 135)
			(layer "B.Fab")
			(hide yes)
			(effects
				(font
					(size 1 1)
					(thickness 0.15)
				)
				(justify mirror)
			)
		)
		(property "Public" ""
			(at 323.23721 57.589586 135)
			(layer "B.Fab")
			(hide yes)
			(effects
				(font
					(size 1 1)
					(thickness 0.15)
				)
				(justify mirror)
			)
		)
		(property "Tolerance" "1%"
			(at 323.23721 57.589586 135)
			(layer "B.Fab")
			(hide yes)
			(effects
				(font
					(size 1 1)
					(thickness 0.15)
				)
				(justify mirror)
			)
		)
		(property "Val" "1k65"
			(at 323.23721 57.589586 135)
			(layer "B.Fab")
			(hide yes)
			(effects
				(font
					(size 1 1)
					(thickness 0.15)
				)
				(justify mirror)
			)
		)
		(sheetname "/Power/")
		(sheetfile "power.kicad_sch")
		(attr smd)
		(fp_poly
			(pts
				(xy -0.925 0.47) (xy 0.925 0.47) (xy 0.925 -0.47) (xy -0.925 -0.47)
			)
			(stroke
				(width 0.05)
				(type default)
			)
			(fill no)
			(layer "B.CrtYd")
		)
		(fp_poly
			(pts
				(xy -0.5 0.25) (xy 0.5 0.25) (xy 0.5 -0.25) (xy -0.5 -0.25)
			)
			(stroke
				(width 0.15)
				(type solid)
			)
			(fill no)
			(layer "B.Fab")
		)
		(pad "1" smd roundrect
			(at -0.48 0 90)
			(size 0.59 0.64)
			(layers "B.Cu" "B.Mask" "B.Paste")
			(roundrect_rratio 0.25)
			(net 1 "GND")
			(pintype "passive")
		)
		(pad "2" smd roundrect
			(at 0.48 0 90)
			(size 0.59 0.64)
			(layers "B.Cu" "B.Mask" "B.Paste")
			(roundrect_rratio 0.25)
			(net 141 "Net-(D17-C)")
			(pintype "passive")
		)
	)
	(footprint "antmicro-footprints:TP_SMD_0.75mm"
		(layer "B.Cu")
		(at 147.828 97.89 180)
		(property "Reference" "TP18"
			(at 0 0.6 0)
			(layer "B.SilkS")
			(hide yes)
			(effects
				(font
					(size 0.7 0.7)
					(thickness 0.15)
				)
				(justify left bottom mirror)
			)
		)
		(property "Value" "TP_0.75mm_SMD"
			(at 0 -1.2 0)
			(layer "B.Fab")
			(effects
				(font
					(size 0.7 0.7)
					(thickness 0.15)
				)
				(justify left bottom mirror)
			)
		)
		(property "Description" "SMT test point"
			(at 0 0 0)
			(layer "B.Fab")
			(hide yes)
			(effects
				(font
					(size 1.27 1.27)
					(thickness 0.15)
				)
				(justify mirror)
			)
		)
		(property "MPN" ""
			(at 0 0 0)
			(unlocked yes)
			(layer "B.Fab")
			(hide yes)
			(effects
				(font
					(size 1 1)
					(thickness 0.15)
				)
				(justify mirror)
			)
		)
		(property "Manufacturer" ""
			(at 0 0 0)
			(unlocked yes)
			(layer "B.Fab")
			(hide yes)
			(effects
				(font
					(size 1 1)
					(thickness 0.15)
				)
				(justify mirror)
			)
		)
		(property "Author" "Antmicro"
			(at 0 0 0)
			(unlocked yes)
			(layer "B.Fab")
			(hide yes)
			(effects
				(font
					(size 1 1)
					(thickness 0.15)
				)
				(justify mirror)
			)
		)
		(property "License" "Apache-2.0"
			(at 0 0 0)
			(unlocked yes)
			(layer "B.Fab")
			(hide yes)
			(effects
				(font
					(size 1 1)
					(thickness 0.15)
				)
				(justify mirror)
			)
		)
		(sheetname "/Power/")
		(sheetfile "power.kicad_sch")
		(attr exclude_from_pos_files)
		(fp_circle
			(center 0 0)
			(end 0.475 0)
			(stroke
				(width 0.05)
				(type default)
			)
			(fill no)
			(layer "B.CrtYd")
		)
		(fp_text user "Author: Antmicro"
			(at -0.4 -3.901 0)
			(layer "B.Fab")
			(effects
				(font
					(size 0.7 0.7)
					(thickness 0.15)
				)
				(justify left bottom mirror)
			)
		)
		(fp_text user "${REFERENCE}"
			(at -0.4 -2.7 0)
			(layer "B.Fab")
			(effects
				(font
					(size 0.7 0.7)
					(thickness 0.15)
				)
				(justify left bottom mirror)
			)
		)
		(fp_text user "License: Apache-2.0"
			(at -0.4 -5.101 0)
			(layer "B.Fab")
			(effects
				(font
					(size 0.7 0.7)
					(thickness 0.15)
				)
				(justify left bottom mirror)
			)
		)
		(pad "1" smd circle
			(at 0 0 180)
			(size 0.75 0.75)
			(layers "B.Cu" "B.Mask")
			(net 123 "/Power/OUT_12V")
			(pinfunction "1")
			(pintype "passive")
		)
	)
	(footprint "antmicro-footprints:R_0402_1005Metric"
		(layer "B.Cu")
		(at 133.791 87.334 180)
		(descr "Resistor SMD 0402")
		(tags "resistor SMD 0402")
		(property "Reference" "R53"
			(at -1.083 -1.266 0)
			(layer "B.SilkS")
			(effects
				(font
					(size 0.7 0.7)
					(thickness 0.15)
				)
				(justify left bottom mirror)
			)
		)
		(property "Value" "R_0R_0402"
			(at -1.011843 -1.772047 0)
			(layer "B.Fab")
			(effects
				(font
					(size 0.7 0.7)
					(thickness 0.15)
				)
				(justify left bottom mirror)
			)
		)
		(property "Datasheet" "https://industrial.panasonic.com/cdbs/www-data/pdf/RDA0000/AOA0000C301.pdf"
			(at 0 0 180)
			(layer "F.Fab")
			(hide yes)
			(effects
				(font
					(size 1.27 1.27)
					(thickness 0.15)
				)
			)
		)
		(property "Description" "SMD Chip Resistor, Jumper, 0 ohm, 100 mW, 0402 [1005 Metric], Thick Film, General Purpose"
			(at 0 0 180)
			(layer "F.Fab")
			(hide yes)
			(effects
				(font
					(size 1.27 1.27)
					(thickness 0.15)
				)
			)
		)
		(property "Author" "Antmicro"
			(at 267.582 174.668 0)
			(layer "B.Fab")
			(hide yes)
			(effects
				(font
					(size 1 1)
					(thickness 0.15)
				)
				(justify mirror)
			)
		)
		(property "Current" "1A"
			(at 267.582 174.668 0)
			(layer "B.Fab")
			(hide yes)
			(effects
				(font
					(size 1 1)
					(thickness 0.15)
				)
				(justify mirror)
			)
		)
		(property "License" "Apache-2.0"
			(at 267.582 174.668 0)
			(layer "B.Fab")
			(hide yes)
			(effects
				(font
					(size 1 1)
					(thickness 0.15)
				)
				(justify mirror)
			)
		)
		(property "MPN" "ERJ2GE0R00X"
			(at 267.582 174.668 0)
			(layer "B.Fab")
			(hide yes)
			(effects
				(font
					(size 1 1)
					(thickness 0.15)
				)
				(justify mirror)
			)
		)
		(property "Manufacturer" "Panasonic"
			(at 267.582 174.668 0)
			(layer "B.Fab")
			(hide yes)
			(effects
				(font
					(size 1 1)
					(thickness 0.15)
				)
				(justify mirror)
			)
		)
		(property "Tolerance" ""
			(at 267.582 174.668 0)
			(layer "B.Fab")
			(hide yes)
			(effects
				(font
					(size 1 1)
					(thickness 0.15)
				)
				(justify mirror)
			)
		)
		(property "Val" "0R"
			(at 267.582 174.668 0)
			(layer "B.Fab")
			(hide yes)
			(effects
				(font
					(size 1 1)
					(thickness 0.15)
				)
				(justify mirror)
			)
		)
		(sheetname "/Deserializer/")
		(sheetfile "deserializer.kicad_sch")
		(attr smd)
		(fp_rect
			(start -0.925 0.47)
			(end 0.925 -0.47)
			(stroke
				(width 0.05)
				(type default)
			)
			(fill no)
			(layer "B.CrtYd")
		)
		(fp_rect
			(start -0.5 0.25)
			(end 0.5 -0.25)
			(stroke
				(width 0.15)
				(type solid)
			)
			(fill no)
			(layer "B.Fab")
		)
		(pad "1" smd roundrect
			(at -0.48 0 180)
			(size 0.59 0.64)
			(layers "B.Cu" "B.Mask" "B.Paste")
			(roundrect_rratio 0.25)
			(net 27 "/Deserializer/VDD")
			(pintype "passive")
		)
		(pad "2" smd roundrect
			(at 0.48 0 180)
			(size 0.59 0.64)
			(layers "B.Cu" "B.Mask" "B.Paste")
			(roundrect_rratio 0.25)
			(net 73 "+1V2")
			(pintype "passive")
		)
	)
	(footprint "antmicro-footprints:TP_SMD_0.75mm"
		(layer "B.Cu")
		(at 156.972 97.89 180)
		(property "Reference" "TP24"
			(at 0 0.6 0)
			(layer "B.SilkS")
			(hide yes)
			(effects
				(font
					(size 0.7 0.7)
					(thickness 0.15)
				)
				(justify left bottom mirror)
			)
		)
		(property "Value" "TP_0.75mm_SMD"
			(at 0 -1.2 0)
			(layer "B.Fab")
			(effects
				(font
					(size 0.7 0.7)
					(thickness 0.15)
				)
				(justify left bottom mirror)
			)
		)
		(property "Description" "SMT test point"
			(at 0 0 0)
			(layer "B.Fab")
			(hide yes)
			(effects
				(font
					(size 1.27 1.27)
					(thickness 0.15)
				)
				(justify mirror)
			)
		)
		(property "MPN" ""
			(at 0 0 0)
			(unlocked yes)
			(layer "B.Fab")
			(hide yes)
			(effects
				(font
					(size 1 1)
					(thickness 0.15)
				)
				(justify mirror)
			)
		)
		(property "Manufacturer" ""
			(at 0 0 0)
			(unlocked yes)
			(layer "B.Fab")
			(hide yes)
			(effects
				(font
					(size 1 1)
					(thickness 0.15)
				)
				(justify mirror)
			)
		)
		(property "Author" "Antmicro"
			(at 0 0 0)
			(unlocked yes)
			(layer "B.Fab")
			(hide yes)
			(effects
				(font
					(size 1 1)
					(thickness 0.15)
				)
				(justify mirror)
			)
		)
		(property "License" "Apache-2.0"
			(at 0 0 0)
			(unlocked yes)
			(layer "B.Fab")
			(hide yes)
			(effects
				(font
					(size 1 1)
					(thickness 0.15)
				)
				(justify mirror)
			)
		)
		(sheetname "/Connectors/")
		(sheetfile "connectors.kicad_sch")
		(attr exclude_from_pos_files)
		(fp_circle
			(center 0 0)
			(end 0.475 0)
			(stroke
				(width 0.05)
				(type default)
			)
			(fill no)
			(layer "B.CrtYd")
		)
		(fp_text user "Author: Antmicro"
			(at -0.4 -3.901 0)
			(layer "B.Fab")
			(effects
				(font
					(size 0.7 0.7)
					(thickness 0.15)
				)
				(justify left bottom mirror)
			)
		)
		(fp_text user "License: Apache-2.0"
			(at -0.4 -5.101 0)
			(layer "B.Fab")
			(effects
				(font
					(size 0.7 0.7)
					(thickness 0.15)
				)
				(justify left bottom mirror)
			)
		)
		(fp_text user "${REFERENCE}"
			(at -0.4 -2.7 0)
			(layer "B.Fab")
			(effects
				(font
					(size 0.7 0.7)
					(thickness 0.15)
				)
				(justify left bottom mirror)
			)
		)
		(pad "1" smd circle
			(at 0 0 180)
			(size 0.75 0.75)
			(layers "B.Cu" "B.Mask")
			(net 50 "/Connectors/FFC_3V3")
			(pinfunction "1")
			(pintype "passive")
		)
	)
	(footprint "antmicro-footprints:C_0402_1005Metric"
		(layer "B.Cu")
		(at 151.384 84.836 135)
		(descr "Capacitor SMD 0402")
		(tags "capacitor SMD 0402")
		(property "Reference" "C37"
			(at -0.97797 -1.314712 315)
			(unlocked yes)
			(layer "B.SilkS")
			(effects
				(font
					(size 0.7 0.7)
					(thickness 0.15)
				)
				(justify right bottom mirror)
			)
		)
		(property "Value" "C_10u_0402"
			(at -1.022927 -2.155213 135)
			(layer "B.Fab")
			(effects
				(font
					(size 0.7 0.7)
					(thickness 0.15)
				)
				(justify right bottom mirror)
			)
		)
		(property "Datasheet" "https://www.yageo.com/en/Chart/Download/pdf/CC0402MRX5R5BB106"
			(at 0 0 135)
			(layer "F.Fab")
			(hide yes)
			(effects
				(font
					(size 1.27 1.27)
					(thickness 0.15)
				)
			)
		)
		(property "Description" "SMD Multilayer Ceramic Capacitor, 10 µF, 6.3 V, 0402 [1005 Metric], ± 20%, X5R, CC Series"
			(at 0 0 135)
			(layer "F.Fab")
			(hide yes)
			(effects
				(font
					(size 1.27 1.27)
					(thickness 0.15)
				)
			)
		)
		(property "Author" "Antmicro"
			(at 318.416764 37.779458 0)
			(layer "B.Fab")
			(hide yes)
			(effects
				(font
					(size 1 1)
					(thickness 0.15)
				)
				(justify mirror)
			)
		)
		(property "Dielectric" ""
			(at 318.416764 37.779458 0)
			(layer "B.Fab")
			(hide yes)
			(effects
				(font
					(size 1 1)
					(thickness 0.15)
				)
				(justify mirror)
			)
		)
		(property "License" "Apache-2.0"
			(at 318.416764 37.779458 0)
			(layer "B.Fab")
			(hide yes)
			(effects
				(font
					(size 1 1)
					(thickness 0.15)
				)
				(justify mirror)
			)
		)
		(property "MPN" "CC0402MRX5R5BB106"
			(at 318.416764 37.779458 0)
			(layer "B.Fab")
			(hide yes)
			(effects
				(font
					(size 1 1)
					(thickness 0.15)
				)
				(justify mirror)
			)
		)
		(property "Manufacturer" "YAGEO"
			(at 318.416764 37.779458 0)
			(layer "B.Fab")
			(hide yes)
			(effects
				(font
					(size 1 1)
					(thickness 0.15)
				)
				(justify mirror)
			)
		)
		(property "Val" "10u"
			(at 318.416764 37.779458 0)
			(layer "B.Fab")
			(hide yes)
			(effects
				(font
					(size 1 1)
					(thickness 0.15)
				)
				(justify mirror)
			)
		)
		(property "Voltage" ""
			(at 318.416764 37.779458 0)
			(layer "B.Fab")
			(hide yes)
			(effects
				(font
					(size 1 1)
					(thickness 0.15)
				)
				(justify mirror)
			)
		)
		(sheetname "/Deserializer/")
		(sheetfile "deserializer.kicad_sch")
		(attr smd)
		(fp_poly
			(pts
				(xy -0.925 0.47) (xy 0.925 0.47) (xy 0.925 -0.47) (xy -0.925 -0.47)
			)
			(stroke
				(width 0.05)
				(type default)
			)
			(fill no)
			(layer "B.CrtYd")
		)
		(fp_line
			(start 0.504 -0.248)
			(end 0.504 0.25)
			(stroke
				(width 0.15)
				(type solid)
			)
			(layer "B.Fab")
		)
		(fp_line
			(start 0.504 0.25)
			(end -0.494 0.25)
			(stroke
				(width 0.15)
				(type solid)
			)
			(layer "B.Fab")
		)
		(fp_line
			(start -0.494 -0.248)
			(end 0.504 -0.248)
			(stroke
				(width 0.15)
				(type solid)
			)
			(layer "B.Fab")
		)
		(fp_line
			(start -0.494 0.25)
			(end -0.494 -0.248)
			(stroke
				(width 0.15)
				(type solid)
			)
			(layer "B.Fab")
		)
		(pad "1" smd roundrect
			(at -0.48 0 135)
			(size 0.59 0.64)
			(layers "B.Cu" "B.Mask" "B.Paste")
			(roundrect_rratio 0.25)
			(net 1 "GND")
			(pintype "passive")
		)
		(pad "2" smd roundrect
			(at 0.48 0 135)
			(size 0.59 0.64)
			(layers "B.Cu" "B.Mask" "B.Paste")
			(roundrect_rratio 0.25)
			(net 27 "/Deserializer/VDD")
			(pintype "passive")
		)
	)
)
